# S9S_MB_2U (Grand Teton) — schematic netlist excerpt (pin names and nets, part order shuffled) for the footprints in the layout excerpt that follows; sources: Cadence DE-HDL packaged netlist, KiCad conversion of 03242023_DA0F0TMBIJ0_F0T_Motherboard_J_brd_V01_OCP.brd

J35  SCONN168_ME1016810202011  IO  pkg CON_F168S2H7D_P0-6W2-95_LUH  page 159
  GND_A1  = GND
  GND_A2  = GND
  GND_A3  = GND
  GND_A4  = GND
  GND_A5  = GND
  GND_A6  = GND
  SMCLK  = SMB_OCP_V3_2_3V3AUX_BUF_R_SCL
  SMDAT  = SMB_OCP_V3_2_3V3AUX_BUF_R_SDA
  \smrst#\  = RST_SMB_OCP_V3_2_N
  \prsnta#\  = OCP_V3_1_PRSNTA_R_N
  \perst1#\  = RST_PERST1_OCP_V3_2_N
  \prsntb2#\  = OCP_V3_2_PRSNT2_R_N
  GND_A13  = GND
  REFCLKN1  = CLK_100M_OCP_V3_2_B_DN
  REFCLKP1  = CLK_100M_OCP_V3_2_B_DP
  GND_A16  = GND
  PERN0  = P5E_CPU1_PE1_RX_DN<0>
  PERP0  = P5E_CPU1_PE1_RX_DP<0>
  GND_A19  = GND
  PERN1  = P5E_CPU1_PE1_RX_DN<1>
  PERP1  = P5E_CPU1_PE1_RX_DP<1>
  GND_A22  = GND
  PERN2  = P5E_CPU1_PE1_RX_DN<2>
  PERP2  = P5E_CPU1_PE1_RX_DP<2>
  GND_A25  = GND
  PERN3  = P5E_CPU1_PE1_RX_DN<3>
  PERP3  = P5E_CPU1_PE1_RX_DP<3>
  GND_A28  = GND
  GND_A29  = GND
  PERN4  = P5E_CPU1_PE1_RX_DN<4>
  PERP4  = P5E_CPU1_PE1_RX_DP<4>
  GND_A32  = GND
  PERN5  = P5E_CPU1_PE1_RX_DN<5>
  PERP5  = P5E_CPU1_PE1_RX_DP<5>
  GND_A35  = GND
  PERN6  = P5E_CPU1_PE1_RX_DN<6>
  PERP6  = P5E_CPU1_PE1_RX_DP<6>
  GND_A38  = GND
  PERN7  = P5E_CPU1_PE1_RX_DN<7>
  PERP7  = P5E_CPU1_PE1_RX_DP<7>
  GND_A41  = GND
  \prsntb1#\  = OCP_V3_2_PRSNT1_R_N
  GND_A43  = GND
  PERN8  = P5E_CPU1_PE1_RX_DN<8>
  PERP8  = P5E_CPU1_PE1_RX_DP<8>
  GND_A46  = GND
  PERN9  = P5E_CPU1_PE1_RX_DN<9>
  PERP9  = P5E_CPU1_PE1_RX_DP<9>
  GND_A49  = GND
  PERN10  = P5E_CPU1_PE1_RX_DN<10>
  PERP10  = P5E_CPU1_PE1_RX_DP<10>
  GND_A52  = GND
  PERN11  = P5E_CPU1_PE1_RX_DN<11>
  PERP11  = P5E_CPU1_PE1_RX_DP<11>
  GND_A55  = GND
  PERN12  = P5E_CPU1_PE1_RX_DN<12>
  PERP12  = P5E_CPU1_PE1_RX_DP<12>
  GND_A58  = GND
  PERN13  = P5E_CPU1_PE1_RX_DN<13>
  PERP13  = P5E_CPU1_PE1_RX_DP<13>
  GND_A61  = GND
  PERN14  = P5E_CPU1_PE1_RX_DN<14>
  PERP14  = P5E_CPU1_PE1_RX_DP<14>
  GND_A64  = GND
  PERN15  = P5E_CPU1_PE1_RX_DN<15>
  PERP15  = P5E_CPU1_PE1_RX_DP<15>
  GND_A67  = GND
  USB_DATN  = USB2_5_R1_DN
  USB_DATP  = USB2_5_R1_DP
  \pwrbrk0#\  = OCP_V3_2_PWRBRK_N
  \+12v_edge_b1\  = P12V_OCP_V3_2
  \+12v_edge_b2\  = P12V_OCP_V3_2
  \+12v_edge_b3\  = P12V_OCP_V3_2
  \+12v_edge_b4\  = P12V_OCP_V3_2
  \+12v_edge_b5\  = P12V_OCP_V3_2
  \+12v_edge_b6\  = P12V_OCP_V3_2
  \bif0#\  = OCP_V3_2_BIF0_R_N
  \bif1#\  = OCP_V3_2_BIF1_R_N
  \bif2#\  = OCP_V3_2_BIF2_R_N
  \perst0#\  = RST_PERST0_OCP_V3_2_N
  \+3.3v_edge\  = P3V3_OCP_V3_2
  AUX_PWR_EN  = OCP_V3_2_AUX_PWR_EN_R
  GND_B13  = GND
  REFCLKN0  = CLK_100M_OCP_V3_2_A_DN
  REFCLKP0  = CLK_100M_OCP_V3_2_A_DP
  GND_B16  = GND
  PETN0  = P5E_CPU1_PE1_TX_C_DP<0>
  PETP0  = P5E_CPU1_PE1_TX_C_DN<0>
  GND_B19  = GND
  PETN1  = P5E_CPU1_PE1_TX_C_DN<1>
  PETP1  = P5E_CPU1_PE1_TX_C_DP<1>
  GND_B22  = GND
  PETN2  = P5E_CPU1_PE1_TX_C_DP<2>
  PETP2  = P5E_CPU1_PE1_TX_C_DN<2>
  GND_B25  = GND
  PETN3  = P5E_CPU1_PE1_TX_C_DN<3>
  PETP3  = P5E_CPU1_PE1_TX_C_DP<3>
  GND_B28  = GND
  GND_B29  = GND
  PETN4  = P5E_CPU1_PE1_TX_C_DP<4>
  PETP4  = P5E_CPU1_PE1_TX_C_DN<4>
  GND_B32  = GND
  PETN5  = P5E_CPU1_PE1_TX_C_DN<5>
  PETP5  = P5E_CPU1_PE1_TX_C_DP<5>
  GND_B35  = GND
  PETN6  = P5E_CPU1_PE1_TX_C_DP<6>
  PETP6  = P5E_CPU1_PE1_TX_C_DN<6>
  GND_B38  = GND
  PETN7  = P5E_CPU1_PE1_TX_C_DN<7>
  PETP7  = P5E_CPU1_PE1_TX_C_DP<7>
  GND_B41  = GND
  \prsntb0#\  = OCP_V3_2_PRSNT0_R_N
  GND_B43  = GND
  PETN8  = P5E_CPU1_PE1_TX_C_DP<8>
  PETP8  = P5E_CPU1_PE1_TX_C_DN<8>
  GND_B46  = GND
  PETN9  = P5E_CPU1_PE1_TX_C_DN<9>
  PETP9  = P5E_CPU1_PE1_TX_C_DP<9>
  GND_B49  = GND
  PETN10  = P5E_CPU1_PE1_TX_C_DP<10>
  PETP10  = P5E_CPU1_PE1_TX_C_DN<10>
  GND_B52  = GND
  PETN11  = P5E_CPU1_PE1_TX_C_DN<11>
  PETP11  = P5E_CPU1_PE1_TX_C_DP<11>
  GND_B55  = GND
  PETN12  = P5E_CPU1_PE1_TX_C_DP<12>
  PETP12  = P5E_CPU1_PE1_TX_C_DN<12>
  GND_B58  = GND
  PETN13  = P5E_CPU1_PE1_TX_C_DN<13>
  PETP13  = P5E_CPU1_PE1_TX_C_DP<13>
  GND_B61  = GND
  PETN14  = P5E_CPU1_PE1_TX_C_DP<14>
  PETP14  = P5E_CPU1_PE1_TX_C_DN<14>
  GND_B64  = GND
  PETN15  = P5E_CPU1_PE1_TX_C_DN<15>
  PETP15  = P5E_CPU1_PE1_TX_C_DP<15>
  GND_B67  = GND
  RFU1_NC_B68  = TP_OCP_V3_2_B68
  RFU1_NC_B69  = TP_OCP_V3_2_B69
  \prsntb3#\  = OCP_V3_2_PRSNT3_R_N
  G1  = GND
  G2  = GND
  G3  = GND
  G4  = GND
  G5  = GND
  \perst2#\  = RST_PERST2_OCP_V3_2_N
  \perst3#\  = RST_PERST3_OCP_V3_2_N
  \wake#\  = IRQ_LVC3_OCP_V3_2_WAKE_N
  RBT_ARB_IN  = OCP_V3_2_ISO1_RBT_ARB_IN
  RBT_ARB_OUT  = OCP_V3_2_ISO2_RBT_ARB_OUT
  SLOT_ID1  = OCP_V3_2_ID1
  RBT_TX_EN  = NCSI_OCP_V3_2_TX_EN
  RBT_TXD1  = NCSI_OCP_V3_2_TXD1
  RBT_TXD0  = NCSI_OCP_V3_2_TXD0
  GND_OA10  = GND
  REFCLKN3  = CLK_100M_OCP_V3_2_D_DN
  REFCLKP3  = CLK_100M_OCP_V3_2_D_DP
  GND_OA13  = GND
  RBT_CLK_IN  = CLK_50M_NCSI_OCP_V3_2_ISO
  NIC_PWR_GOOD  = FM_OCP_V3_2_PWR_GOOD
  MAIN_PWR_EN  = OCP_V3_2_MAIN_PWR_EN_R
  \ld#\  = SGPIO_OCP_V3_2_LD_N
  DATA_IN  = SGPIO_OCP_V3_2_DATAIN
  DATA_OUT  = SGPIO_OCP_V3_2_DATAOUT
  CLK  = SGPIO_OCP_V3_2_CLK
  SLOT_ID0  = OCP_V3_2_ID0
  RBT_RXD1  = NCSI_OCP_V3_2_RXD1
  RBT_RXD0  = NCSI_OCP_V3_2_RXD0
  GND_OB10  = GND
  REFCLKN2  = CLK_100M_OCP_V3_2_C_DN
  REFCLKP2  = CLK_100M_OCP_V3_2_C_DP
  GND_OB13  = GND
  RBT_CRS_DV  = NCSI_OCP_V3_2_CRS_DV

(kicad_pcb
	(version 20260206)
	(generator "pcbnew")
	(generator_version "10.0")
	(general
		(thickness 1.6)
		(legacy_teardrops no)
	)
	(paper "A4")
	(title_block
		(title "03242023_DA0F0TMBIJ0_F0T_Motherboard_J_brd_V01_OCP.brd")
		(comment 1 "Grand Teton / footprint 3456 of 6105 (J35), pads 175-175 of 175")
	)
	(layers
		(0 "F.Cu" signal "TOP")
		(4 "In1.Cu" signal "GND")
		(6 "In2.Cu" signal "IN1")
		(8 "In3.Cu" signal "GND1")
		(10 "In4.Cu" signal "IN2")
		(12 "In5.Cu" signal "GND2")
		(14 "In6.Cu" signal "IN3")
		(16 "In7.Cu" signal "GND3")
		(18 "In8.Cu" signal "VCC")
		(20 "In9.Cu" signal "VCC1")
		(22 "In10.Cu" signal "GND4")
		(24 "In11.Cu" signal "IN4")
		(26 "In12.Cu" signal "GND5")
		(28 "In13.Cu" signal "IN5")
		(30 "In14.Cu" signal "GND6")
		(32 "In15.Cu" signal "IN6")
		(34 "In16.Cu" signal "GND7")
		(2 "B.Cu" signal "BOTTOM")
		(9 "F.Adhes" user "F.Adhesive")
		(11 "B.Adhes" user "B.Adhesive")
		(13 "F.Paste" user "Package Geometry/Pastemask Top")
		(15 "B.Paste" user "Package Geometry/Pastemask Bottom")
		(5 "F.SilkS" user "Ref Des/Silkscreen Top")
		(7 "B.SilkS" user "Ref Des/Silkscreen Bottom")
		(1 "F.Mask" user "Board Geometry/Soldermask Top")
		(3 "B.Mask" user "Board Geometry/Soldermask Bottom")
		(17 "Dwgs.User" user "User.Drawings")
		(19 "Cmts.User" user "User.Comments")
		(21 "Eco1.User" user "User.Eco1")
		(23 "Eco2.User" user "User.Eco2")
		(25 "Edge.Cuts" user "Board Geometry/Outline")
		(27 "Margin" user)
		(31 "F.CrtYd" user "Package Geometry/Place Bound Top")
		(29 "B.CrtYd" user "Package Geometry/Place Bound Bottom")
		(35 "F.Fab" user "Ref Des/Assembly Top")
		(33 "B.Fab" user "Ref Des/Assembly Bottom")
	)
	(footprint ""
		(layer "F.Cu")
		(at 47.401988 -5.569966 -90)
		(property "Reference" "J35"
			(at -16.848074 29.242004 0)
			(unlocked yes)
			(layer "F.SilkS")
			(effects
				(font
					(size 0.7874 0.5842)
					(thickness 0.1524)
				)
				(justify left)
			)
		)
		(property "Value" ""
			(at 0 0 270)
			(layer "F.Fab")
			(effects
				(font
					(size 1.27 1.27)
				)
			)
		)
		(duplicate_pad_numbers_are_jumpers no)
		(pad "OB14" smd rect
			(at -5.700014 -22.86 180)
			(size 0.381 1.4478)
			(layers "F.Cu" "F.Mask" "F.Paste")
			(net "NCSI_OCP_V3_2_CRS_DV")
		)
	)
)
